# S9S_MB_2U (Grand Teton) — schematic netlist excerpt (pin names and nets, part order shuffled) for the footprints in the layout excerpt that follows; sources: Cadence DE-HDL packaged netlist, KiCad conversion of 03242023_DA0F0TMBIJ0_F0T_Motherboard_J_brd_V01_OCP.brd

PR833  Q_RES  1.5K 1% EMPTY  pkg 0402LF  page 259 : A = P3V3_AUX_SS ; B = GND
C219  Q_CAP  47UF 4V 20% X6S  pkg C0805  page 74 : A = PVCCIN_CPU0 ; B = GND
C1990  Q_CAP_DIFFBUS  DIFF BUS_0.22UF 6.3V 20% X6S  pkg C0201  page 181 : \1\ = P3E_PCH_E1S_TX_DN<3> ; \2\ = P3E_PCH_E1S_TX_C_DN<3>

(kicad_pcb
	(version 20260206)
	(generator "pcbnew")
	(generator_version "10.0")
	(general
		(thickness 1.6)
		(legacy_teardrops no)
	)
	(paper "A4")
	(title_block
		(title "03242023_DA0F0TMBIJ0_F0T_Motherboard_J_brd_V01_OCP.brd")
		(comment 1 "Grand Teton / footprints 4141-4143 of 6105")
	)
	(layers
		(0 "F.Cu" signal "TOP")
		(4 "In1.Cu" signal "GND")
		(6 "In2.Cu" signal "IN1")
		(8 "In3.Cu" signal "GND1")
		(10 "In4.Cu" signal "IN2")
		(12 "In5.Cu" signal "GND2")
		(14 "In6.Cu" signal "IN3")
		(16 "In7.Cu" signal "GND3")
		(18 "In8.Cu" signal "VCC")
		(20 "In9.Cu" signal "VCC1")
		(22 "In10.Cu" signal "GND4")
		(24 "In11.Cu" signal "IN4")
		(26 "In12.Cu" signal "GND5")
		(28 "In13.Cu" signal "IN5")
		(30 "In14.Cu" signal "GND6")
		(32 "In15.Cu" signal "IN6")
		(34 "In16.Cu" signal "GND7")
		(2 "B.Cu" signal "BOTTOM")
		(9 "F.Adhes" user "F.Adhesive")
		(11 "B.Adhes" user "B.Adhesive")
		(13 "F.Paste" user "Package Geometry/Pastemask Top")
		(15 "B.Paste" user "Package Geometry/Pastemask Bottom")
		(5 "F.SilkS" user "Ref Des/Silkscreen Top")
		(7 "B.SilkS" user "Ref Des/Silkscreen Bottom")
		(1 "F.Mask" user "Board Geometry/Soldermask Top")
		(3 "B.Mask" user "Board Geometry/Soldermask Bottom")
		(17 "Dwgs.User" user "User.Drawings")
		(19 "Cmts.User" user "User.Comments")
		(21 "Eco1.User" user "User.Eco1")
		(23 "Eco2.User" user "User.Eco2")
		(25 "Edge.Cuts" user "Board Geometry/Outline")
		(27 "Margin" user)
		(31 "F.CrtYd" user "Package Geometry/Place Bound Top")
		(29 "B.CrtYd" user "Package Geometry/Place Bound Bottom")
		(35 "F.Fab" user "Ref Des/Assembly Top")
		(33 "B.Fab" user "Ref Des/Assembly Bottom")
	)
	(footprint ""
		(layer "F.Cu")
		(at 366.06988 -296.05478 180)
		(property "Reference" "C219"
			(at 0 0 180)
			(layer "F.SilkS")
			(hide yes)
			(effects
				(font
					(size 1.27 1.27)
				)
			)
		)
		(property "Value" ""
			(at 0 0 180)
			(layer "F.Fab")
			(effects
				(font
					(size 1.27 1.27)
				)
			)
		)
		(duplicate_pad_numbers_are_jumpers no)
		(fp_line
			(start 1.524 0.762)
			(end -1.524 0.762)
			(stroke
				(width 0.1524)
				(type default)
			)
			(layer "F.SilkS")
		)
		(fp_line
			(start 1.524 -0.762)
			(end 1.524 0.762)
			(stroke
				(width 0.1524)
				(type default)
			)
			(layer "F.SilkS")
		)
		(fp_line
			(start -1.524 0.762)
			(end -1.524 -0.762)
			(stroke
				(width 0.1524)
				(type default)
			)
			(layer "F.SilkS")
		)
		(fp_line
			(start -1.524 -0.762)
			(end 1.524 -0.762)
			(stroke
				(width 0.1524)
				(type default)
			)
			(layer "F.SilkS")
		)
		(fp_line
			(start 1.1049 0.724916)
			(end 1.1049 -0.724916)
			(stroke
				(width 0.1)
				(type default)
			)
			(layer "F.Fab")
		)
		(fp_line
			(start 1.1049 -0.724916)
			(end -1.1049 -0.724916)
			(stroke
				(width 0.1)
				(type default)
			)
			(layer "F.Fab")
		)
		(fp_line
			(start -1.1049 0.724916)
			(end 1.1049 0.724916)
			(stroke
				(width 0.1)
				(type default)
			)
			(layer "F.Fab")
		)
		(fp_line
			(start -1.1049 -0.724916)
			(end -1.1049 0.724916)
			(stroke
				(width 0.1)
				(type default)
			)
			(layer "F.Fab")
		)
		(pad "1" smd rect
			(at -0.889 0)
			(size 1.016 1.27)
			(layers "F.Cu" "F.Mask" "F.Paste")
			(net "PVCCIN_CPU0")
		)
		(pad "2" smd rect
			(at 0.889 0)
			(size 1.016 1.27)
			(layers "F.Cu" "F.Mask" "F.Paste")
			(net "GND")
		)
	)
	(footprint ""
		(layer "F.Cu")
		(at 239.152684 -57.41289 180)
		(property "Reference" "C1990"
			(at 0 0 180)
			(layer "F.SilkS")
			(hide yes)
			(effects
				(font
					(size 1.27 1.27)
				)
			)
		)
		(property "Value" ""
			(at 0 0 180)
			(layer "F.Fab")
			(effects
				(font
					(size 1.27 1.27)
				)
			)
		)
		(duplicate_pad_numbers_are_jumpers no)
		(fp_line
			(start 0.299974 0.150114)
			(end -0.299974 0.150114)
			(stroke
				(width 0.1)
				(type default)
			)
			(layer "F.Fab")
		)
		(fp_line
			(start 0.299974 -0.150114)
			(end 0.299974 0.150114)
			(stroke
				(width 0.1)
				(type default)
			)
			(layer "F.Fab")
		)
		(fp_line
			(start -0.299974 0.150114)
			(end -0.299974 -0.150114)
			(stroke
				(width 0.1)
				(type default)
			)
			(layer "F.Fab")
		)
		(fp_line
			(start -0.299974 -0.150114)
			(end 0.299974 -0.150114)
			(stroke
				(width 0.1)
				(type default)
			)
			(layer "F.Fab")
		)
		(pad "1" smd rect
			(at -0.2667 0 180)
			(size 0.3048 0.381)
			(layers "F.Cu" "F.Mask" "F.Paste")
			(net "P3E_PCH_E1S_TX_DN<3>")
		)
		(pad "2" smd rect
			(at 0.2667 0 180)
			(size 0.3048 0.381)
			(layers "F.Cu" "F.Mask" "F.Paste")
			(net "P3E_PCH_E1S_TX_C_DN<3>")
		)
		(zone
			(layer "In1.Cu")
			(hatch none 0.5)
			(connect_pads
				(clearance 0)
			)
			(min_thickness 0.25)
			(keepout
				(tracks not_allowed)
				(vias allowed)
				(pads allowed)
				(copperpour not_allowed)
				(footprints allowed)
			)
			(placement
				(enabled no)
				(sheetname "")
			)
			(fill
				(thermal_gap 0.5)
				(thermal_bridge_width 0.5)
				(island_removal_mode 0)
			)
			(polygon
				(pts
					(arc
						(start 239.012984 -57.653174)
						(mid 239.066866 -57.630856)
						(end 239.089184 -57.576974)
					)
					(arc
						(start 239.089184 -57.246774)
						(mid 239.066866 -57.192892)
						(end 239.012984 -57.170574)
					)
					(arc
						(start 238.758984 -57.170574)
						(mid 238.705102 -57.192892)
						(end 238.682784 -57.246774)
					)
					(arc
						(start 238.682784 -57.576974)
						(mid 238.705102 -57.630856)
						(end 238.758984 -57.653174)
					)
				)
			)
		)
		(zone
			(layer "In1.Cu")
			(hatch none 0.5)
			(connect_pads
				(clearance 0)
			)
			(min_thickness 0.25)
			(keepout
				(tracks not_allowed)
				(vias allowed)
				(pads allowed)
				(copperpour not_allowed)
				(footprints allowed)
			)
			(placement
				(enabled no)
				(sheetname "")
			)
			(fill
				(thermal_gap 0.5)
				(thermal_bridge_width 0.5)
				(island_removal_mode 0)
			)
			(polygon
				(pts
					(arc
						(start 239.546384 -57.653174)
						(mid 239.600266 -57.630856)
						(end 239.622584 -57.576974)
					)
					(arc
						(start 239.622584 -57.246774)
						(mid 239.600266 -57.192892)
						(end 239.546384 -57.170574)
					)
					(arc
						(start 239.292384 -57.170574)
						(mid 239.238502 -57.192892)
						(end 239.216184 -57.246774)
					)
					(arc
						(start 239.216184 -57.576974)
						(mid 239.238502 -57.630856)
						(end 239.292384 -57.653174)
					)
				)
			)
		)
	)
	(footprint ""
		(layer "F.Cu")
		(at 450.307202 -77.829918 90)
		(property "Reference" "PR833"
			(at 0 0 90)
			(layer "F.SilkS")
			(hide yes)
			(effects
				(font
					(size 1.27 1.27)
				)
			)
		)
		(property "Value" ""
			(at 0 0 90)
			(layer "F.Fab")
			(effects
				(font
					(size 1.27 1.27)
				)
			)
		)
		(duplicate_pad_numbers_are_jumpers no)
		(fp_line
			(start 0.7874 -0.4064)
			(end 0.7874 0.4064)
			(stroke
				(width 0.1524)
				(type default)
			)
			(layer "F.SilkS")
		)
		(fp_line
			(start -0.7874 -0.4064)
			(end 0.7874 -0.4064)
			(stroke
				(width 0.1524)
				(type default)
			)
			(layer "F.SilkS")
		)
		(fp_line
			(start 0.7874 0.4064)
			(end -0.7874 0.4064)
			(stroke
				(width 0.1524)
				(type default)
			)
			(layer "F.SilkS")
		)
		(fp_line
			(start -0.7874 0.4064)
			(end -0.7874 -0.4064)
			(stroke
				(width 0.1524)
				(type default)
			)
			(layer "F.SilkS")
		)
		(fp_line
			(start -0.12065 -0.305054)
			(end -0.12065 -0.2794)
			(stroke
				(width 0.1)
				(type default)
			)
			(layer "F.Fab")
		)
		(fp_line
			(start -0.67945 -0.305054)
			(end -0.12065 -0.305054)
			(stroke
				(width 0.1)
				(type default)
			)
			(layer "F.Fab")
		)
		(fp_line
			(start 0.67945 -0.3048)
			(end 0.67945 0.3048)
			(stroke
				(width 0.1)
				(type default)
			)
			(layer "F.Fab")
		)
		(fp_line
			(start 0.12065 -0.3048)
			(end 0.67945 -0.3048)
			(stroke
				(width 0.1)
				(type default)
			)
			(layer "F.Fab")
		)
		(fp_line
			(start 0.12065 -0.2794)
			(end 0.12065 -0.3048)
			(stroke
				(width 0.1)
				(type default)
			)
			(layer "F.Fab")
		)
		(fp_line
			(start -0.12065 -0.2794)
			(end 0.12065 -0.2794)
			(stroke
				(width 0.1)
				(type default)
			)
			(layer "F.Fab")
		)
		(fp_line
			(start 0.120396 0.2794)
			(end -0.12065 0.2794)
			(stroke
				(width 0.1)
				(type default)
			)
			(layer "F.Fab")
		)
		(fp_line
			(start -0.12065 0.2794)
			(end -0.12065 0.3048)
			(stroke
				(width 0.1)
				(type default)
			)
			(layer "F.Fab")
		)
		(fp_line
			(start 0.67945 0.3048)
			(end 0.120396 0.3048)
			(stroke
				(width 0.1)
				(type default)
			)
			(layer "F.Fab")
		)
		(fp_line
			(start 0.120396 0.3048)
			(end 0.120396 0.2794)
			(stroke
				(width 0.1)
				(type default)
			)
			(layer "F.Fab")
		)
		(fp_line
			(start -0.12065 0.3048)
			(end -0.67945 0.3048)
			(stroke
				(width 0.1)
				(type default)
			)
			(layer "F.Fab")
		)
		(fp_line
			(start -0.67945 0.3048)
			(end -0.67945 -0.305054)
			(stroke
				(width 0.1)
				(type default)
			)
			(layer "F.Fab")
		)
		(pad "1" smd circle
			(at -0.40005 0 90)
			(size 0 0)
			(layers "F.Cu" "F.Mask" "F.Paste")
			(net "P3V3_AUX_SS")
		)
		(pad "2" smd circle
			(at 0.40005 0 90)
			(size 0 0)
			(layers "F.Cu" "F.Mask" "F.Paste")
			(net "GND")
		)
	)
)
